FILE_TYPE = CONNECTIVITY;
{Allegro Design Entry HDL 17.4-2019 S026 (4007227) 1/17/2022}
"PAGE_NUMBER" = 137;
0"NC";
1"GND\g";
2"GND\g";
3"GND\g";
4"GND\g";
5"P3V3\g";
6"P3V3\g";
7"P3V3\g";
8"PVDD18_S5_P0\g";
9"PVDD18_S5_P0\g";
10"GND\g";
11"P3V3_AUX\g";
12"GND\g";
13"GND\g";
14"GND\g";
15"P3V3_AUX\g";
16"PVDD11_S3_P0\g";
17"PVDD11_S3_P0\g";
18"GND\g";
19"SMB_CPU0_CPU1_APML_BUF2_SCL_R1";
20"SMB_CPU0_CPU1_APML_BUF2_SDA_R1";
21"PVDD11_S3_P0\g";
22"SMB_CPU0_CPU1_APML_SCL";
23"SMB_CPU0_CPU1_APML_BUF1_SCL_R2";
24"SMB_CPU0_CPU1_SEC_SDA_R2";
25"SMB_CPU0_CPU1_SEC_SCL_R2";
26"SMB_CPU0_CPU1_APML_BUF1_SDA_R2";
27"SMB_CPU0_CPU1_SEC_SDA";
28"PU_U96_EN";
29"SMB_CPU0_CPU1_SEC_SCL";
30"SMB_CPU0_CPU1_SEC_SDA_R2";
31"SMB_CPU0_CPU1_SEC_SCL_R2";
32"SMB_CPU0_CPU1_SEC_SDA_R1";
33"SMB_CPU0_CPU1_SEC_SCL_R1";
34"SMB_CPU0_CPU1_APML_SCL";
35"SMB_CPU0_CPU1_APML_BUF1_SDA_R2";
36"SMB_CPU0_CPU1_APML_BUF1_SCL_R2";
37"SMB_CPU0_CPU1_APML_BUF1_SDA";
38"SMB_CPU0_CPU1_APML_BUF1_SCL";
39"SMB_CPU0_CPU1_APML_BUF1_SCL_R1";
40"SMB_CPU0_CPU1_APML_BUF1_SDA_R1";
41"PU_U5_EN";
42"SMB_CPU0_CPU1_APML_SDA";
43"SMB_CPU0_CPU1_APML_SDA";
44"SMB_CPU0_CPU1_APML_BUF2_SCL";
45"SMB_CPU0_CPU1_APML_BUF2_SDA";
46"PU_U2_EN";
47"SMB_CPU0_CPU1_APML_BUF2_SDA_R2";
48"SMB_CPU0_CPU1_APML_BUF2_SCL_R2";
49"SMB_CPU0_CPU1_APML_SCL_R2";
50"SMB_CPU0_CPU1_APML_BUF2_SCL_R2";
51"SMB_CPU0_CPU1_APML_SCL_R2";
52"SMB_CPU0_CPU1_APML_SDA_R2";
53"SMB_CPU0_CPU1_APML_BUF2_SDA_R2";
54"SMB_CPU0_CPU1_APML_SDA_R2";
55"P3V3_AUX\g";
56"P3V3_AUX\g";
57"PVDD18_S5_P0\g";
58"P3V3\g";
59"P3V3_AUX\g";
%"Q_RES"
"2","(-6825,-2250)","0","pure_quanta","I13";
;
LOCATION"R200"
$SEC"1"
CDS_SEC"1"
TOLERANCE"5%"
MATERIAL"EMPTY"
PACK_TYPE"0402LF"
WATTAGE"1/16W"
VALUE"4.7K"
CDS_LIB"pure_quanta"
PART_NUMBER"CS24702JB10";
"A"
$PN"1"11;
"B"
$PN"2"28;
%"Q_RES"
"1","(-3900,-1675)","0","pure_quanta","I15";
;
LOCATION"R1154"
$SEC"1"
CDS_SEC"1"
VALUE"0"
CDS_LIB"pure_quanta"
WATTAGE"1/16W"
MATERIAL"CHIP"
TOLERANCE"5%"
PACK_TYPE"0402LF"
PART_NUMBER"CS00002JB13";
"B"
$PN"2"30;
"A"
$PN"1"32;
%"Q_RES"
"1","(-3900,-1575)","0","pure_quanta","I16";
;
LOCATION"R1153"
$SEC"1"
CDS_SEC"1"
VALUE"0"
CDS_LIB"pure_quanta"
WATTAGE"1/16W"
MATERIAL"CHIP"
TOLERANCE"5%"
PACK_TYPE"0402LF"
PART_NUMBER"CS00002JB13";
"B"
$PN"2"31;
"A"
$PN"1"33;
%"UNIVERSAL_GND"
"1","(-6500,1925)","0","pure_quanta_power","I24";
;
CDS_LIB"pure_quanta_power"
HDL_POWER"GND";
"A"1;
%"UNIVERSAL_GND"
"1","(-6650,2550)","0","pure_quanta_power","I25";
;
CDS_LIB"pure_quanta_power"
HDL_POWER"GND";
"A"2;
%"Q_CAP"
"1","(-6650,2750)","0","pure_quanta","I26";
;
LOCATION"C23"
$SEC"1"
CDS_SEC"1"
TOLERANCE"10%"
VOLTAGE"25V"
MATERIAL"X7R"
PACK_TYPE"0402"
VALUE"0.1UF"
CDS_LIB"pure_quanta"
PART_NUMBER"CH4104K1B00";
"B"
$PN"2"2;
"A"
$PN"1"59;
%"UNIVERSAL_POWER"
"1","(-6475,3025)","2","pure_quanta_power","I27";
;
HDL_POWER"P3V3_AUX"
CDS_LIB"pure_quanta_power";
"A"59;
%"UNIVERSAL_GND"
"1","(-5325,2550)","0","pure_quanta_power","I28";
;
CDS_LIB"pure_quanta_power"
HDL_POWER"GND";
"A"3;
%"Q_CAP"
"1","(-5325,2750)","0","pure_quanta","I29";
;
LOCATION"C26"
$SEC"1"
CDS_SEC"1"
PACK_TYPE"0402"
MATERIAL"X7R"
TOLERANCE"10%"
VOLTAGE"25V"
VALUE"0.1UF"
CDS_LIB"pure_quanta"
PART_NUMBER"CH4104K1B00";
"B"
$PN"2"3;
"A"
$PN"1"58;
%"UNIVERSAL_GND"
"1","(-5050,-2075)","0","pure_quanta_power","I3";
;
CDS_LIB"pure_quanta_power"
HDL_POWER"GND";
"A"4;
%"VCC_CORE"
"1","(-5400,3000)","0","pure_quanta_power","I30";
;
HDL_POWER"P3V3"
CDS_LIB"pure_quanta_power";
"A"58;
%"Q_RES"
"2","(-4225,1775)","0","pure_quanta","I31";
;
LOCATION"R78"
$SEC"1"
CDS_SEC"1"
TOLERANCE"5%"
VALUE"4.7K"
WATTAGE"1/16W"
MATERIAL"EMPTY"
PACK_TYPE"0402LF"
CDS_LIB"pure_quanta"
PART_NUMBER"CS24702JB10";
"A"
$PN"1"5;
"B"
$PN"2"41;
%"VCC_CORE"
"1","(-4225,2050)","0","pure_quanta_power","I32";
;
HDL_POWER"P3V3"
CDS_LIB"pure_quanta_power";
"A"5;
%"Q_RES"
"2","(-1550,-150)","0","pure_quanta","I40";
;
LOCATION"R361"
$SEC"1"
CDS_SEC"1"
VALUE"4.7K"
TOLERANCE"5%"
PACK_TYPE"0402LF"
MATERIAL"EMPTY"
WATTAGE"1/16W"
CDS_LIB"pure_quanta"
PART_NUMBER"CS24702JB10";
"A"
$PN"1"6;
"B"
$PN"2"23;
%"Q_RES"
"2","(-1225,-150)","0","pure_quanta","I41";
;
LOCATION"R365"
$SEC"1"
CDS_SEC"1"
WATTAGE"1/16W"
MATERIAL"EMPTY"
PACK_TYPE"0402LF"
VALUE"4.7K"
TOLERANCE"5%"
CDS_LIB"pure_quanta"
PART_NUMBER"CS24702JB10";
"A"
$PN"1"7;
"B"
$PN"2"26;
%"VCC_CORE"
"1","(-1550,100)","0","pure_quanta_power","I42";
;
HDL_POWER"P3V3"
CDS_LIB"pure_quanta_power";
"A"6;
%"VCC_CORE"
"1","(-1225,100)","0","pure_quanta_power","I43";
;
HDL_POWER"P3V3"
CDS_LIB"pure_quanta_power";
"A"7;
%"Q_RES"
"2","(-925,-150)","0","pure_quanta","I44";
;
LOCATION"R368"
$SEC"1"
CDS_SEC"1"
WATTAGE"1/16W"
PACK_TYPE"0402LF"
MATERIAL"EMPTY"
VALUE"4.7K"
TOLERANCE"5%"
CDS_LIB"pure_quanta"
PART_NUMBER"CS24702JB10";
"A"
$PN"1"8;
"B"
$PN"2"25;
%"VCC_CORE"
"1","(-925,100)","0","pure_quanta_power","I45";
;
HDL_POWER"PVDD18_S5_P0"
CDS_LIB"pure_quanta_power";
"A"8;
%"Q_RES"
"2","(-650,-150)","0","pure_quanta","I46";
;
LOCATION"R406"
$SEC"1"
CDS_SEC"1"
WATTAGE"1/16W"
MATERIAL"EMPTY"
VALUE"4.7K"
TOLERANCE"5%"
PACK_TYPE"0402LF"
CDS_LIB"pure_quanta"
PART_NUMBER"CS24702JB10";
"A"
$PN"1"9;
"B"
$PN"2"24;
%"PCA9617ADP"
"1","(-5975,2300)","0","pure_quanta","I48";
;
LOCATION"U5"
$SEC"1"
CDS_SEC"1"
MATERIAL"EMPTY"
PART_TYPE"SMLF"
VALUE"PCA9617ADP"
CDS_LMAN_SYM_OUTLINE"-275,300,275,-300"
CDS_LIB"pure_quanta"
NEEDS_NO_SIZE"TRUE"
PART_NUMBER"AL009617K02";
"GND"
$PN"4"1;
"SCLB"
$PN"7"39;
"SDAB"
$PN"6"40;
"SDAA"
$PN"3"37;
"SCLA"
$PN"2"38;
"VCCB"
$PN"8"58;
"VCCA"
$PN"1"59;
"EN"
$PN"5"41;
%"VCC_CORE"
"1","(-650,175)","0","pure_quanta_power","I49";
;
HDL_POWER"PVDD18_S5_P0"
CDS_LIB"pure_quanta_power";
"A"9;
%"UNIVERSAL_GND"
"1","(-6450,-1375)","0","pure_quanta_power","I5";
;
CDS_LIB"pure_quanta_power"
HDL_POWER"GND";
"A"10;
%"VCC_CORE"
"1","(-5200,-925)","0","pure_quanta_power","I50";
;
HDL_POWER"PVDD18_S5_P0"
CDS_LIB"pure_quanta_power";
"A"57;
%"PCA9617ADP"
"1","(-5775,-1625)","2","pure_quanta","I51";
;
LOCATION"U96"
SEC"1"
VALUE"PCA9617ADP"
PART_TYPE"SMLF"
MATERIAL"IC"
SEC_TYPE""
CDS_LMAN_SYM_OUTLINE"-275,300,275,-300"
NEEDS_NO_SIZE"TRUE"
CDS_LIB"pure_quanta"
PART_NUMBER"AL009617K02";
"GND"
$PN"4"4;
"SCLB"
$PN"7"29;
"SDAB"
$PN"6"27;
"SDAA"
$PN"3"32;
"SCLA"
$PN"2"33;
"VCCB"
$PN"8"55;
"VCCA"
$PN"1"57;
"EN"
$PN"5"28;
%"UNIVERSAL_POWER"
"1","(-6825,-1975)","2","pure_quanta_power","I52";
;
HDL_POWER"P3V3_AUX"
CDS_LIB"pure_quanta_power";
"A"11;
%"VCC_CORE"
"1","(-5350,1375)","0","pure_quanta_power","I54";
;
HDL_POWER"PVDD11_S3_P0"
CDS_LIB"pure_quanta_power";
"A"21;
%"UNIVERSAL_GND"
"1","(-5275,950)","0","pure_quanta_power","I55";
;
CDS_LIB"pure_quanta_power"
HDL_POWER"GND";
"A"12;
%"Q_CAP"
"1","(-5275,1150)","0","pure_quanta","I56";
;
LOCATION"C3"
$SEC"1"
CDS_SEC"1"
PACK_TYPE"0402"
MATERIAL"X7R"
VALUE"0.1UF"
TOLERANCE"10%"
VOLTAGE"25V"
CDS_LIB"pure_quanta"
PART_NUMBER"CH4104K1B00";
"B"
$PN"2"12;
"A"
$PN"1"21;
%"UNIVERSAL_POWER"
"1","(-6500,1475)","2","pure_quanta_power","I57";
;
HDL_POWER"P3V3_AUX"
CDS_LIB"pure_quanta_power";
"A"56;
%"UNIVERSAL_GND"
"1","(-6675,1000)","0","pure_quanta_power","I58";
;
CDS_LIB"pure_quanta_power"
HDL_POWER"GND";
"A"13;
%"Q_CAP"
"1","(-6675,1200)","0","pure_quanta","I59";
;
LOCATION"C2"
$SEC"1"
CDS_SEC"1"
MATERIAL"X7R"
TOLERANCE"10%"
VALUE"0.1UF"
VOLTAGE"25V"
PACK_TYPE"0402"
CDS_LIB"pure_quanta"
PART_NUMBER"CH4104K1B00";
"B"
$PN"2"13;
"A"
$PN"1"56;
%"Q_CAP"
"1","(-6450,-1175)","0","pure_quanta","I6";
;
LOCATION"C611"
$SEC"1"
CDS_SEC"1"
VOLTAGE"25V"
VALUE"0.1UF"
TOLERANCE"10%"
PACK_TYPE"0402"
MATERIAL"X7R"
CDS_LIB"pure_quanta"
PART_NUMBER"CH4104K1B00";
"B"
$PN"2"10;
"A"
$PN"1"55;
%"UNIVERSAL_GND"
"1","(-5400,375)","0","pure_quanta_power","I60";
;
CDS_LIB"pure_quanta_power"
HDL_POWER"GND";
"A"14;
%"UNIVERSAL_POWER"
"1","(-7050,400)","2","pure_quanta_power","I61";
;
HDL_POWER"P3V3_AUX"
CDS_LIB"pure_quanta_power";
"A"15;
%"Q_RES"
"2","(-7050,125)","0","pure_quanta","I62";
;
LOCATION"R201"
$SEC"1"
CDS_SEC"1"
VALUE"4.7K"
PACK_TYPE"0402LF"
MATERIAL"EMPTY"
WATTAGE"1/16W"
TOLERANCE"5%"
CDS_LIB"pure_quanta"
PART_NUMBER"CS24702JB10";
"A"
$PN"1"15;
"B"
$PN"2"46;
%"Q_RES"
"1","(-4400,800)","0","pure_quanta","I67";
;
LOCATION"R202"
$SEC"1"
CDS_SEC"1"
MATERIAL"CHIP"
VALUE"0"
PACK_TYPE"0402LF"
WATTAGE"1/16W"
TOLERANCE"5%"
CDS_LIB"pure_quanta"
PART_NUMBER"CS00002JB13";
"B"
$PN"2"50;
"A"
$PN"1"19;
%"Q_RES"
"1","(-4375,700)","0","pure_quanta","I68";
;
LOCATION"R206"
$SEC"1"
CDS_SEC"1"
MATERIAL"CHIP"
PACK_TYPE"0402LF"
VALUE"0"
CDS_LIB"pure_quanta"
WATTAGE"1/16W"
TOLERANCE"5%"
PART_NUMBER"CS00002JB13";
"B"
$PN"2"53;
"A"
$PN"1"20;
%"UNIVERSAL_POWER"
"1","(-6275,-900)","2","pure_quanta_power","I7";
;
HDL_POWER"P3V3_AUX"
CDS_LIB"pure_quanta_power";
"A"55;
%"Q_RES"
"1","(-2350,800)","0","pure_quanta","I71";
;
LOCATION"R274"
$SEC"1"
CDS_SEC"1"
PACK_TYPE"0402LF"
MATERIAL"CHIP"
VALUE"0"
WATTAGE"1/16W"
TOLERANCE"5%"
CDS_LIB"pure_quanta"
PART_NUMBER"CS00002JB13";
"B"
$PN"2"51;
"A"
$PN"1"50;
%"Q_RES"
"1","(-2325,700)","0","pure_quanta","I72";
;
LOCATION"R281"
$SEC"1"
CDS_SEC"1"
PACK_TYPE"0402LF"
VALUE"0"
MATERIAL"CHIP"
WATTAGE"1/16W"
TOLERANCE"5%"
CDS_LIB"pure_quanta"
PART_NUMBER"CS00002JB13";
"B"
$PN"2"54;
"A"
$PN"1"53;
%"Q_RES"
"2","(-1750,-150)","0","pure_quanta","I73";
;
LOCATION"R322"
$SEC"1"
CDS_SEC"1"
MATERIAL"EMPTY"
WATTAGE"1/16W"
TOLERANCE"1%"
VALUE"1K"
PACK_TYPE"0402LF"
CDS_LIB"pure_quanta"
PART_NUMBER"CS21002FB06";
"A"
$PN"1"16;
"B"
$PN"2"48;
%"VCC_CORE"
"1","(-1750,75)","0","pure_quanta_power","I74";
;
HDL_POWER"PVDD11_S3_P0"
CDS_LIB"pure_quanta_power";
"A"16;
%"VCC_CORE"
"1","(-2000,125)","0","pure_quanta_power","I77";
;
HDL_POWER"PVDD11_S3_P0"
CDS_LIB"pure_quanta_power";
"A"17;
%"Q_RES"
"2","(-2000,-100)","0","pure_quanta","I78";
;
LOCATION"R290"
$SEC"1"
CDS_SEC"1"
TOLERANCE"1%"
VALUE"1K"
MATERIAL"EMPTY"
WATTAGE"1/16W"
PACK_TYPE"0402LF"
CDS_LIB"pure_quanta"
PART_NUMBER"CS21002FB06";
"A"
$PN"1"17;
"B"
$PN"2"47;
%"Q_RES"
"1","(-7750,800)","0","pure_quanta","I79";
;
LOCATION"R151"
$SEC"1"
CDS_SEC"1"
MATERIAL"CHIP"
VALUE"0"
PACK_TYPE"0402LF"
CDS_LIB"pure_quanta"
WATTAGE"1/16W"
TOLERANCE"5%"
PART_NUMBER"CS00002JB13";
"B"
$PN"2"44;
"A"
$PN"1"22;
%"Q_CAP"
"1","(-5125,-1175)","0","pure_quanta","I8";
;
LOCATION"C612"
$SEC"1"
CDS_SEC"1"
VALUE"0.1UF"
MATERIAL"X7R"
TOLERANCE"10%"
PACK_TYPE"0402"
VOLTAGE"25V"
CDS_LIB"pure_quanta"
PART_NUMBER"CH4104K1B00";
"B"
$PN"2"18;
"A"
$PN"1"57;
%"Q_RES"
"1","(-7750,700)","0","pure_quanta","I80";
;
LOCATION"R162"
$SEC"1"
CDS_SEC"1"
VALUE"0"
PACK_TYPE"0402LF"
MATERIAL"CHIP"
CDS_LIB"pure_quanta"
TOLERANCE"5%"
WATTAGE"1/16W"
PART_NUMBER"CS00002JB13";
"B"
$PN"2"45;
"A"
$PN"1"42;
%"UNIVERSAL_GND"
"1","(-5125,-1375)","0","pure_quanta_power","I9";
;
CDS_LIB"pure_quanta_power"
HDL_POWER"GND";
"A"18;
%"Q_RES"
"1","(-2725,2250)","0","pure_quanta","I91";
;
LOCATION"R257"
$SEC"1"
CDS_SEC"1"
VALUE"0"
MATERIAL"EMPTY"
PACK_TYPE"0402LF"
TOLERANCE"5%"
WATTAGE"1/16W"
CDS_LIB"pure_quanta"
PART_NUMBER"CS00002JB13";
"B"
$PN"2"52;
"A"
$PN"1"35;
%"Q_RES"
"1","(-2750,2350)","0","pure_quanta","I92";
;
LOCATION"R256"
$SEC"1"
CDS_SEC"1"
VALUE"0"
MATERIAL"EMPTY"
WATTAGE"1/16W"
TOLERANCE"5%"
PACK_TYPE"0402LF"
CDS_LIB"pure_quanta"
PART_NUMBER"CS00002JB13";
"B"
$PN"2"49;
"A"
$PN"1"36;
%"Q_RES"
"1","(-4100,2350)","0","pure_quanta","I93";
;
LOCATION"R1151"
$SEC"1"
CDS_SEC"1"
VALUE"0"
MATERIAL"EMPTY"
CDS_LIB"pure_quanta"
WATTAGE"1/16W"
TOLERANCE"5%"
PACK_TYPE"0402LF"
PART_NUMBER"CS00002JB13";
"B"
$PN"2"36;
"A"
$PN"1"39;
%"Q_RES"
"1","(-4100,2250)","0","pure_quanta","I94";
;
LOCATION"R1152"
$SEC"1"
CDS_SEC"1"
MATERIAL"EMPTY"
VALUE"0"
CDS_LIB"pure_quanta"
PACK_TYPE"0402LF"
TOLERANCE"5%"
WATTAGE"1/16W"
PART_NUMBER"CS00002JB13";
"B"
$PN"2"35;
"A"
$PN"1"40;
%"Q_RES"
"1","(-5975,3325)","0","pure_quanta","I95";
;
LOCATION"R790"
$SEC"1"
CDS_SEC"1"
VALUE"0"
MATERIAL"EMPTY"
PACK_TYPE"0402LF"
TOLERANCE"5%"
WATTAGE"1/16W"
CDS_LIB"pure_quanta"
PART_NUMBER"CS00002JB13";
"B"
$PN"2"40;
"A"
$PN"1"37;
%"Q_RES"
"1","(-5975,3375)","0","pure_quanta","I96";
;
LOCATION"R789"
$SEC"1"
CDS_SEC"1"
VALUE"0"
MATERIAL"EMPTY"
WATTAGE"1/16W"
TOLERANCE"5%"
PACK_TYPE"0402LF"
CDS_LIB"pure_quanta"
PART_NUMBER"CS00002JB13";
"B"
$PN"2"39;
"A"
$PN"1"38;
%"Q_RES"
"1","(-7850,2250)","0","pure_quanta","I97";
;
LOCATION"R150"
$SEC"1"
CDS_SEC"1"
VALUE"0"
MATERIAL"EMPTY"
CDS_LIB"pure_quanta"
PACK_TYPE"0402LF"
TOLERANCE"5%"
WATTAGE"1/16W"
PART_NUMBER"CS00002JB13";
"B"
$PN"2"37;
"A"
$PN"1"43;
%"Q_RES"
"1","(-7850,2350)","0","pure_quanta","I98";
;
LOCATION"R140"
$SEC"1"
CDS_SEC"1"
VALUE"0"
MATERIAL"EMPTY"
CDS_LIB"pure_quanta"
WATTAGE"1/16W"
TOLERANCE"5%"
PACK_TYPE"0402LF"
PART_NUMBER"CS00002JB13";
"B"
$PN"2"38;
"A"
$PN"1"34;
%"PCA9617ADP"
"1","(-6000,750)","2","pure_quanta","I99";
;
LOCATION"U2"
SEC"1"
VALUE"PCA9617ADP"
MATERIAL"IC"
PART_TYPE"SMLF"
CDS_LMAN_SYM_OUTLINE"-275,300,275,-300"
NEEDS_NO_SIZE"TRUE"
CDS_LIB"pure_quanta"
SEC_TYPE""
PART_NUMBER"AL009617K02";
"GND"
$PN"4"14;
"SCLB"
$PN"7"44;
"SDAB"
$PN"6"45;
"SDAA"
$PN"3"20;
"SCLA"
$PN"2"19;
"VCCB"
$PN"8"56;
"VCCA"
$PN"1"21;
"EN"
$PN"5"46;
END.
